# BARRELEYE_G2-BPX24-EVT-HW-EBOM-X00_20161124-add_2nd_source_X09-20161207-Final.xls — TBD AVL Qual (bom)
| NOTES: |  |  |  |  |  |  |
| The following items are alternates to the items listed in the Critical Components Qual tab. |  |  |  |  |  |  |
| These components will be included on near future, non-customer builds for validation and approval by both Customer and the ODM. |  |  |  |  |  |  |
| Item Description | ODM P/N | Customer PN | Vendor | Vendor PN | Build ?? | Estimated Completion Date |
| SATA connectors (black) |  |  |  |  |  |  |
| -  Alternate |  |  |  |  |  |  |
| SATA connectors (blue) |  |  |  |  |  |  |
| -  Alternate |  |  |  |  |  |  |
| PCIe retention |  |  |  |  |  |  |
| -  Alternate |  |  |  |  |  |  |
| RTC XTAL |  |  |  |  |  |  |
| -  Alternate |  |  |  |  |  |  |
| XTAL |  |  |  |  |  |  |
| -  Alternate |  |  |  |  |  |  |
